(kicad_pcb
	(version 20260206)
	(generator "pcbnew")
	(generator_version "10.0")
	(general
		(thickness 1.6)
		(legacy_teardrops no)
	)
	(paper "A4")
	(title_block
		(title "Bryce Canyon_Front Panel_16369-1_OCP.brd")
		(comment 1 "Bryce Canyon / footprints 70-73 of 154")
	)
	(layers
		(0 "F.Cu" signal "TOP")
		(4 "In1.Cu" signal "L2GND")
		(6 "In2.Cu" signal "L3VCC")
		(2 "B.Cu" signal "BOTTOM")
		(9 "F.Adhes" user "F.Adhesive")
		(11 "B.Adhes" user "B.Adhesive")
		(13 "F.Paste" user "Package Geometry/Pastemask Top")
		(15 "B.Paste" user "Package Geometry/Pastemask Bottom")
		(5 "F.SilkS" user "Ref Des/Silkscreen Top")
		(7 "B.SilkS" user "Ref Des/Silkscreen Bottom")
		(1 "F.Mask" user "Board Geometry/Soldermask Top")
		(3 "B.Mask" user "Board Geometry/Soldermask Bottom")
		(17 "Dwgs.User" user "User.Drawings")
		(19 "Cmts.User" user "User.Comments")
		(21 "Eco1.User" user "User.Eco1")
		(23 "Eco2.User" user "User.Eco2")
		(25 "Edge.Cuts" user "Board Geometry/Outline")
		(27 "Margin" user)
		(31 "F.CrtYd" user "Package Geometry/Place Bound Top")
		(29 "B.CrtYd" user "Package Geometry/Place Bound Bottom")
		(35 "F.Fab" user "Ref Des/Assembly Top")
		(33 "B.Fab" user "Ref Des/Assembly Bottom")
	)
	(footprint ""
		(layer "F.Cu")
		(at 55.2196 -50.1142 90)
		(property "Reference" "R40"
			(at 0 0 90)
			(layer "F.SilkS")
			(hide yes)
			(effects
				(font
					(size 1.27 1.27)
				)
			)
		)
		(property "Value" "4K7R2F-GP"
			(at 0.064008 -4.679696 90)
			(unlocked yes)
			(layer "F.Fab")
			(hide yes)
			(effects
				(font
					(size 2.54 2.54)
					(thickness 0.381)
				)
			)
		)
		(property "Device Type" "R402H16"
			(at 0.064008 -6.203696 90)
			(unlocked yes)
			(layer "F.Fab")
			(hide yes)
			(effects
				(font
					(size 2.54 2.54)
					(thickness 0.381)
				)
			)
		)
		(duplicate_pad_numbers_are_jumpers no)
		(fp_line
			(start 0.508 -0.9398)
			(end -0.508 -0.9398)
			(stroke
				(width 0.1524)
				(type default)
			)
			(layer "F.SilkS")
		)
		(fp_line
			(start -0.508 -0.9398)
			(end -0.508 0.9398)
			(stroke
				(width 0.1524)
				(type default)
			)
			(layer "F.SilkS")
		)
		(fp_rect
			(start -0.508 0.9398)
			(end 0.508 -0.9398)
			(stroke
				(width 0)
				(type default)
			)
			(fill no)
			(layer "F.CrtYd")
		)
		(fp_rect
			(start -0.508 0.9398)
			(end 0.508 -0.9398)
			(stroke
				(width 0)
				(type default)
			)
			(fill no)
			(layer "F.Fab")
		)
		(pad "1" smd custom
			(at 0 -0.4445 90)
			(size 0.1397 0.1397)
			(layers "F.Cu" "F.Mask" "F.Paste")
			(net "TEMP_2_A0")
			(options
				(clearance outline)
				(anchor circle)
			)
			(primitives
				(gr_poly
					(pts
						(arc
							(start -0.1778 -0.2794)
							(mid -0.249642 -0.249642)
							(end -0.2794 -0.1778)
						)
						(arc
							(start -0.2794 0.1778)
							(mid -0.249642 0.249642)
							(end -0.1778 0.2794)
						)
						(arc
							(start 0.1778 0.2794)
							(mid 0.249642 0.249642)
							(end 0.2794 0.1778)
						)
						(arc
							(start 0.2794 -0.1778)
							(mid 0.249642 -0.249642)
							(end 0.1778 -0.2794)
						)
					)
					(width 0)
					(fill yes)
				)
			)
		)
		(pad "2" smd custom
			(at 0 0.4445 90)
			(size 0.1397 0.1397)
			(layers "F.Cu" "F.Mask" "F.Paste")
			(net "GND")
			(options
				(clearance outline)
				(anchor circle)
			)
			(primitives
				(gr_poly
					(pts
						(arc
							(start -0.1778 -0.2794)
							(mid -0.249642 -0.249642)
							(end -0.2794 -0.1778)
						)
						(arc
							(start -0.2794 0.1778)
							(mid -0.249642 0.249642)
							(end -0.1778 0.2794)
						)
						(arc
							(start 0.1778 0.2794)
							(mid 0.249642 0.249642)
							(end 0.2794 0.1778)
						)
						(arc
							(start 0.2794 -0.1778)
							(mid 0.249642 -0.249642)
							(end 0.1778 -0.2794)
						)
					)
					(width 0)
					(fill yes)
				)
			)
		)
	)
	(footprint ""
		(layer "F.Cu")
		(at 20.4724 -13.4366)
		(property "Reference" "R2"
			(at 0 0 0)
			(layer "F.SilkS")
			(hide yes)
			(effects
				(font
					(size 1.27 1.27)
				)
			)
		)
		(property "Value" "0R2J-2-GP"
			(at 0.064008 -4.679696 0)
			(unlocked yes)
			(layer "F.Fab")
			(hide yes)
			(effects
				(font
					(size 2.54 2.54)
					(thickness 0.381)
				)
			)
		)
		(property "Device Type" "R402H16"
			(at 0.064008 -6.203696 0)
			(unlocked yes)
			(layer "F.Fab")
			(hide yes)
			(effects
				(font
					(size 2.54 2.54)
					(thickness 0.381)
				)
			)
		)
		(duplicate_pad_numbers_are_jumpers no)
		(fp_line
			(start -0.508 -0.9398)
			(end -0.508 0.9398)
			(stroke
				(width 0.1524)
				(type default)
			)
			(layer "F.SilkS")
		)
		(fp_line
			(start 0.508 -0.9398)
			(end -0.508 -0.9398)
			(stroke
				(width 0.1524)
				(type default)
			)
			(layer "F.SilkS")
		)
		(fp_rect
			(start -0.508 0.9398)
			(end 0.508 -0.9398)
			(stroke
				(width 0)
				(type default)
			)
			(fill no)
			(layer "F.CrtYd")
		)
		(fp_rect
			(start -0.508 0.9398)
			(end 0.508 -0.9398)
			(stroke
				(width 0)
				(type default)
			)
			(fill no)
			(layer "F.Fab")
		)
		(pad "1" smd custom
			(at 0 -0.4445)
			(size 0.1397 0.1397)
			(layers "F.Cu" "F.Mask" "F.Paste")
			(net "UART_SEL_A_MUX")
			(options
				(clearance outline)
				(anchor circle)
			)
			(primitives
				(gr_poly
					(pts
						(arc
							(start -0.1778 -0.2794)
							(mid -0.249642 -0.249642)
							(end -0.2794 -0.1778)
						)
						(arc
							(start -0.2794 0.1778)
							(mid -0.249642 0.249642)
							(end -0.1778 0.2794)
						)
						(arc
							(start 0.1778 0.2794)
							(mid 0.249642 0.249642)
							(end 0.2794 0.1778)
						)
						(arc
							(start 0.2794 -0.1778)
							(mid 0.249642 -0.249642)
							(end 0.1778 -0.2794)
						)
					)
					(width 0)
					(fill yes)
				)
			)
		)
		(pad "2" smd custom
			(at 0 0.4445)
			(size 0.1397 0.1397)
			(layers "F.Cu" "F.Mask" "F.Paste")
			(net "UART_SEL_A_MUX_R")
			(options
				(clearance outline)
				(anchor circle)
			)
			(primitives
				(gr_poly
					(pts
						(arc
							(start -0.1778 -0.2794)
							(mid -0.249642 -0.249642)
							(end -0.2794 -0.1778)
						)
						(arc
							(start -0.2794 0.1778)
							(mid -0.249642 0.249642)
							(end -0.1778 0.2794)
						)
						(arc
							(start 0.1778 0.2794)
							(mid 0.249642 0.249642)
							(end 0.2794 0.1778)
						)
						(arc
							(start 0.2794 -0.1778)
							(mid 0.249642 -0.249642)
							(end 0.1778 -0.2794)
						)
					)
					(width 0)
					(fill yes)
				)
			)
		)
	)
	(footprint ""
		(layer "F.Cu")
		(at 27.3812 -13.1572 90)
		(property "Reference" "C33"
			(at 0 0 90)
			(layer "F.SilkS")
			(hide yes)
			(effects
				(font
					(size 1.27 1.27)
				)
			)
		)
		(property "Value" "SCD1U16V2KX-3GP"
			(at 1.1811 -2.7051 90)
			(unlocked yes)
			(layer "F.Fab")
			(hide yes)
			(effects
				(font
					(size 1.016 1.016)
					(thickness 0.1524)
				)
			)
		)
		(property "Device Type" "C402H22"
			(at 1.1811 -4.2291 90)
			(unlocked yes)
			(layer "F.Fab")
			(hide yes)
			(effects
				(font
					(size 1.016 1.016)
					(thickness 0.1524)
				)
			)
		)
		(duplicate_pad_numbers_are_jumpers no)
		(fp_rect
			(start -0.4318 0.9525)
			(end 0.4318 -0.9525)
			(stroke
				(width 0)
				(type default)
			)
			(fill no)
			(layer "F.CrtYd")
		)
		(fp_rect
			(start -0.4318 0.9525)
			(end 0.4318 -0.9525)
			(stroke
				(width 0)
				(type default)
			)
			(fill no)
			(layer "F.Fab")
		)
		(pad "1" smd custom
			(at 0 -0.4445 90)
			(size 0.1524 0.1524)
			(layers "F.Cu" "F.Mask" "F.Paste")
			(net "D_FLIP_CLR_A#")
			(options
				(clearance outline)
				(anchor circle)
			)
			(primitives
				(gr_poly
					(pts
						(arc
							(start 0.3048 -0.2032)
							(mid 0.275042 -0.275042)
							(end 0.2032 -0.3048)
						)
						(arc
							(start -0.2032 -0.3048)
							(mid -0.275042 -0.275042)
							(end -0.3048 -0.2032)
						)
						(arc
							(start -0.3048 0.2032)
							(mid -0.275042 0.275042)
							(end -0.2032 0.3048)
						)
						(arc
							(start 0.2032 0.3048)
							(mid 0.275042 0.275042)
							(end 0.3048 0.2032)
						)
					)
					(width 0)
					(fill yes)
				)
			)
		)
		(pad "2" smd custom
			(at 0 0.4445 90)
			(size 0.1524 0.1524)
			(layers "F.Cu" "F.Mask" "F.Paste")
			(net "GND")
			(options
				(clearance outline)
				(anchor circle)
			)
			(primitives
				(gr_poly
					(pts
						(arc
							(start 0.3048 -0.2032)
							(mid 0.275042 -0.275042)
							(end 0.2032 -0.3048)
						)
						(arc
							(start -0.2032 -0.3048)
							(mid -0.275042 -0.275042)
							(end -0.3048 -0.2032)
						)
						(arc
							(start -0.3048 0.2032)
							(mid -0.275042 0.275042)
							(end -0.2032 0.3048)
						)
						(arc
							(start 0.2032 0.3048)
							(mid 0.275042 0.275042)
							(end 0.3048 0.2032)
						)
					)
					(width 0)
					(fill yes)
				)
			)
		)
	)
	(footprint ""
		(layer "F.Cu")
		(at 8.199882 -79.499968)
		(property "Reference" "SW1"
			(at 0 0 0)
			(layer "F.SilkS")
			(hide yes)
			(effects
				(font
					(size 1.27 1.27)
				)
			)
		)
		(property "Value" "SW-TACT-6P-100-GP"
			(at 6.9088 -7.239 0)
			(unlocked yes)
			(layer "F.Fab")
			(hide yes)
			(effects
				(font
					(size 2.54 2.54)
					(thickness 0.381)
				)
			)
		)
		(property "Device Type" "PS004-L22NPR1KKK3UBXX"
			(at 6.9088 -8.763 0)
			(unlocked yes)
			(layer "F.Fab")
			(hide yes)
			(effects
				(font
					(size 2.54 2.54)
					(thickness 0.381)
				)
			)
		)
		(duplicate_pad_numbers_are_jumpers no)
		(fp_line
			(start -5.7912 -0.7874)
			(end -5.198618 -0.7874)
			(stroke
				(width 0.1524)
				(type default)
			)
			(layer "F.SilkS")
		)
		(fp_line
			(start -5.7912 0.7874)
			(end -5.7912 -0.7874)
			(stroke
				(width 0.1524)
				(type default)
			)
			(layer "F.SilkS")
		)
		(fp_line
			(start -5.198618 0.7874)
			(end -5.7912 0.7874)
			(stroke
				(width 0.1524)
				(type default)
			)
			(layer "F.SilkS")
		)
		(fp_line
			(start -4.7498 -4.7498)
			(end -2.254758 -4.7498)
			(stroke
				(width 0.1524)
				(type default)
			)
			(layer "F.SilkS")
		)
		(fp_line
			(start -4.7498 -2.254758)
			(end -4.7498 -4.7498)
			(stroke
				(width 0.1524)
				(type default)
			)
			(layer "F.SilkS")
		)
		(fp_line
			(start -4.7498 4.7498)
			(end -4.7498 2.254758)
			(stroke
				(width 0.1524)
				(type default)
			)
			(layer "F.SilkS")
		)
		(fp_line
			(start -2.254758 4.7498)
			(end -4.7498 4.7498)
			(stroke
				(width 0.1524)
				(type default)
			)
			(layer "F.SilkS")
		)
		(fp_line
			(start 0 -1.0922)
			(end 0 -0.4572)
			(stroke
				(width 0.1524)
				(type default)
			)
			(layer "F.SilkS")
		)
		(fp_line
			(start 2.254758 -4.7498)
			(end 4.7498 -4.7498)
			(stroke
				(width 0.1524)
				(type default)
			)
			(layer "F.SilkS")
		)
		(fp_line
			(start 4.1402 -4.8387)
			(end 4.8387 -4.8387)
			(stroke
				(width 0.3302)
				(type default)
			)
			(layer "F.SilkS")
		)
		(fp_line
			(start 4.7498 -4.7498)
			(end 4.7498 -2.254758)
			(stroke
				(width 0.1524)
				(type default)
			)
			(layer "F.SilkS")
		)
		(fp_line
			(start 4.7498 2.254758)
			(end 4.7498 4.7498)
			(stroke
				(width 0.1524)
				(type default)
			)
			(layer "F.SilkS")
		)
		(fp_line
			(start 4.7498 4.7498)
			(end 2.254758 4.7498)
			(stroke
				(width 0.1524)
				(type default)
			)
			(layer "F.SilkS")
		)
		(fp_line
			(start 4.8387 -4.8387)
			(end 4.8387 -4.1656)
			(stroke
				(width 0.3302)
				(type default)
			)
			(layer "F.SilkS")
		)
		(fp_line
			(start 5.198618 -0.7874)
			(end 5.7912 -0.7874)
			(stroke
				(width 0.1524)
				(type default)
			)
			(layer "F.SilkS")
		)
		(fp_line
			(start 5.7912 -0.7874)
			(end 5.7912 0.7874)
			(stroke
				(width 0.1524)
				(type default)
			)
			(layer "F.SilkS")
		)
		(fp_line
			(start 5.7912 0.7874)
			(end 5.198618 0.7874)
			(stroke
				(width 0.1524)
				(type default)
			)
			(layer "F.SilkS")
		)
		(fp_arc
			(start -5.198618 -0.7874)
			(mid -5.028041 -1.537546)
			(end -4.7498 -2.254758)
			(stroke
				(width 0.1524)
				(type default)
			)
			(layer "F.SilkS")
		)
		(fp_arc
			(start -4.7498 2.254758)
			(mid -5.02801 1.537536)
			(end -5.198618 0.7874)
			(stroke
				(width 0.1524)
				(type default)
			)
			(layer "F.SilkS")
		)
		(fp_arc
			(start -2.254758 -4.7498)
			(mid 0 -5.257807)
			(end 2.254758 -4.7498)
			(stroke
				(width 0.1524)
				(type default)
			)
			(layer "F.SilkS")
		)
		(fp_arc
			(start 0 1.016)
			(mid -0.938662 0.388806)
			(end -0.718312 -0.718312)
			(stroke
				(width 0.1524)
				(type default)
			)
			(layer "F.SilkS")
		)
		(fp_arc
			(start 0.718312 -0.718312)
			(mid 0.93852 0.388748)
			(end 0 1.016)
			(stroke
				(width 0.1524)
				(type default)
			)
			(layer "F.SilkS")
		)
		(fp_arc
			(start 2.254758 4.7498)
			(mid 0 5.257807)
			(end -2.254758 4.7498)
			(stroke
				(width 0.1524)
				(type default)
			)
			(layer "F.SilkS")
		)
		(fp_arc
			(start 4.7498 -2.254758)
			(mid 5.02801 -1.537536)
			(end 5.198618 -0.7874)
			(stroke
				(width 0.1524)
				(type default)
			)
			(layer "F.SilkS")
		)
		(fp_arc
			(start 5.198618 0.7874)
			(mid 5.028041 1.537546)
			(end 4.7498 2.254758)
			(stroke
				(width 0.1524)
				(type default)
			)
			(layer "F.SilkS")
		)
		(fp_circle
			(center -4.99999 0)
			(end -4.11099 0)
			(stroke
				(width 0.3048)
				(type default)
			)
			(fill no)
			(layer "F.SilkS")
		)
		(fp_circle
			(center -2.500122 -2.500122)
			(end -1.484122 -2.500122)
			(stroke
				(width 0.3048)
				(type default)
			)
			(fill no)
			(layer "F.SilkS")
		)
		(fp_circle
			(center -2.500122 2.500122)
			(end -1.484122 2.500122)
			(stroke
				(width 0.3048)
				(type default)
			)
			(fill no)
			(layer "F.SilkS")
		)
		(fp_circle
			(center 0 -2.500122)
			(end 1.016 -2.500122)
			(stroke
				(width 0.3048)
				(type default)
			)
			(fill no)
			(layer "F.SilkS")
		)
		(fp_circle
			(center 0 2.500122)
			(end 1.016 2.500122)
			(stroke
				(width 0.3048)
				(type default)
			)
			(fill no)
			(layer "F.SilkS")
		)
		(fp_circle
			(center 2.500122 -2.500122)
			(end 3.516122 -2.500122)
			(stroke
				(width 0.3048)
				(type default)
			)
			(fill no)
			(layer "F.SilkS")
		)
		(fp_circle
			(center 2.500122 2.500122)
			(end 3.516122 2.500122)
			(stroke
				(width 0.3048)
				(type default)
			)
			(fill no)
			(layer "F.SilkS")
		)
		(fp_circle
			(center 4.99999 0)
			(end 5.88899 0)
			(stroke
				(width 0.3048)
				(type default)
			)
			(fill no)
			(layer "F.SilkS")
		)
		(fp_poly
			(pts
				(arc
					(start 2.196846 4.4958)
					(mid 0 5.003834)
					(end -2.196846 4.4958)
				)
				(xy -4.4958 4.4958)
				(arc
					(start -4.4958 2.196846)
					(mid -4.845024 1.250828)
					(end -4.99745 0.254)
				)
				(xy -5.1308 0.254) (xy -5.1308 -0.254)
				(arc
					(start -4.99745 -0.254)
					(mid -4.844994 -1.250821)
					(end -4.4958 -2.196846)
				)
				(xy -4.4958 -4.4958)
				(arc
					(start -2.196846 -4.4958)
					(mid 0 -5.003834)
					(end 2.196846 -4.4958)
				)
				(xy 4.4958 -4.4958)
				(arc
					(start 4.4958 -2.196846)
					(mid 4.845024 -1.250828)
					(end 4.99745 -0.254)
				)
				(xy 5.1308 -0.254) (xy 5.1308 0.254)
				(arc
					(start 4.99745 0.254)
					(mid 4.844994 1.250821)
					(end 4.4958 2.196846)
				)
				(xy 4.4958 4.4958)
			)
			(stroke
				(width 0)
				(type default)
			)
			(fill no)
			(layer "F.CrtYd")
		)
		(fp_poly
			(pts
				(arc
					(start 2.3114 5.0038)
					(mid 0 5.511859)
					(end -2.3114 5.0038)
				)
				(xy -5.0038 5.0038)
				(arc
					(start -5.0038 2.3114)
					(mid -5.246729 1.688816)
					(end -5.412486 1.0414)
				)
				(xy -6.0452 1.0414) (xy -6.0452 -1.0414)
				(arc
					(start -5.412486 -1.0414)
					(mid -5.246693 -1.688804)
					(end -5.0038 -2.3114)
				)
				(xy -5.0038 -5.0038)
				(arc
					(start -2.3114 -5.0038)
					(mid 0 -5.511859)
					(end 2.3114 -5.0038)
				)
				(xy 5.0038 -5.0038)
				(arc
					(start 5.0038 -2.3114)
					(mid 5.246729 -1.688816)
					(end 5.412486 -1.0414)
				)
				(xy 6.0452 -1.0414) (xy 6.0452 -0.00635) (xy 5.1308 -0.00635) (xy 5.1308 -0.254)
				(arc
					(start 4.997704 -0.254)
					(mid 4.845133 -1.250792)
					(end 4.496054 -2.196846)
				)
				(xy 4.4958 -4.4958)
				(arc
					(start 2.196846 -4.4958)
					(mid 0 -5.003834)
					(end -2.196846 -4.4958)
				)
				(xy -4.4958 -4.4958)
				(arc
					(start -4.4958 -2.196846)
					(mid -4.84509 -1.250826)
					(end -4.997704 -0.254)
				)
				(xy -5.1308 -0.254) (xy -5.1308 0.254)
				(arc
					(start -4.997704 0.254)
					(mid -4.845193 1.250762)
					(end -4.496308 2.196846)
				)
				(xy -4.4958 4.4958)
				(arc
					(start -2.196846 4.4958)
					(mid 0 5.003834)
					(end 2.196846 4.4958)
				)
				(xy 4.4958 4.4958)
				(arc
					(start 4.4958 2.196846)
					(mid 4.84509 1.250826)
					(end 4.997704 0.254)
				)
				(xy 5.1308 0.254) (xy 5.1308 0.00635) (xy 6.0452 0.00635) (xy 6.0452 1.0414)
				(arc
					(start 5.412486 1.0414)
					(mid 5.246693 1.688804)
					(end 5.0038 2.3114)
				)
				(xy 5.0038 5.0038)
			)
			(stroke
				(width 0)
				(type default)
			)
			(fill no)
			(layer "F.CrtYd")
		)
		(fp_poly
			(pts
				(arc
					(start 2.3114 5.0038)
					(mid 0 5.511859)
					(end -2.3114 5.0038)
				)
				(xy -5.0038 5.0038)
				(arc
					(start -5.0038 2.3114)
					(mid -5.246729 1.688816)
					(end -5.412486 1.0414)
				)
				(xy -6.0452 1.0414) (xy -6.0452 -1.0414)
				(arc
					(start -5.412486 -1.0414)
					(mid -5.246693 -1.688804)
					(end -5.0038 -2.3114)
				)
				(xy -5.0038 -5.0038)
				(arc
					(start -2.3114 -5.0038)
					(mid 0 -5.511859)
					(end 2.3114 -5.0038)
				)
				(xy 5.0038 -5.0038)
				(arc
					(start 5.0038 -2.3114)
					(mid 5.246729 -1.688816)
					(end 5.412486 -1.0414)
				)
				(xy 6.0452 -1.0414) (xy 6.0452 1.0414)
				(arc
					(start 5.412486 1.0414)
					(mid 5.246693 1.688804)
					(end 5.0038 2.3114)
				)
				(xy 5.0038 5.0038)
			)
			(stroke
				(width 0)
				(type default)
			)
			(fill no)
			(layer "F.Fab")
		)
		(pad "1" thru_hole circle
			(at 2.500122 -2.500122)
			(size 1.3208 1.3208)
			(drill 0.9144)
			(layers "*.Cu" "*.Mask")
			(remove_unused_layers no)
			(net "PWR_BTN_A")
			(clearance 0.1524)
			(thermal_gap 0.1524)
		)
		(pad "2" thru_hole circle
			(at 0 -2.500122)
			(size 1.3208 1.3208)
			(drill 0.9144)
			(layers "*.Cu" "*.Mask")
			(remove_unused_layers no)
			(net "PWR_BTN_A_CONN")
			(clearance 0.1524)
			(thermal_gap 0.1524)
		)
		(pad "3" thru_hole circle
			(at -2.500122 -2.500122)
			(size 1.3208 1.3208)
			(drill 0.9144)
			(layers "*.Cu" "*.Mask")
			(remove_unused_layers no)
			(net "Net_117")
			(clearance 0.1524)
			(thermal_gap 0.1524)
		)
		(pad "4" thru_hole circle
			(at 2.500122 2.500122)
			(size 1.3208 1.3208)
			(drill 0.9144)
			(layers "*.Cu" "*.Mask")
			(remove_unused_layers no)
			(net "GND")
			(clearance 0.1524)
			(thermal_gap 0.1524)
		)
		(pad "5" thru_hole circle
			(at 0 2.500122)
			(size 1.3208 1.3208)
			(drill 0.9144)
			(layers "*.Cu" "*.Mask")
			(remove_unused_layers no)
			(net "PWR_BTN_A_CONN")
			(clearance 0.1524)
			(thermal_gap 0.1524)
		)
		(pad "6" thru_hole circle
			(at -2.500122 2.500122)
			(size 1.3208 1.3208)
			(drill 0.9144)
			(layers "*.Cu" "*.Mask")
			(remove_unused_layers no)
			(net "Net_118")
			(clearance 0.1524)
			(thermal_gap 0.1524)
		)
		(pad "L1" thru_hole circle
			(at 4.99999 0)
			(size 1.0668 1.0668)
			(drill 0.7112)
			(layers "*.Cu" "*.Mask")
			(remove_unused_layers no)
			(net "PWR_BTN_LED_A_R")
			(clearance 0.1778)
			(thermal_gap 0.1778)
		)
		(pad "L2" thru_hole circle
			(at -4.99999 0)
			(size 1.0668 1.0668)
			(drill 0.7112)
			(layers "*.Cu" "*.Mask")
			(remove_unused_layers no)
			(net "PWR_LED_A_N")
			(clearance 0.1778)
			(thermal_gap 0.1778)
		)
	)
)
